FILE_TYPE = CONNECTIVITY;
{Allegro Design Entry HDL 17.2-2016 S081 (4005846) 1/11/2022}
"PAGE_NUMBER" = 73;
0"NC";
1"GND\g";
2"GND\g";
3"GND\g";
4"GND\g";
5"GND\g";
%"UNIVERSAL_GND"
"1","(-3050,-675)","0","logical_power","I1";
;
CDS_LIB"logical_power"
HDL_POWER"GND";
"A"5;
%"SOCKET4677_AZIF0045P001C01CS"
"40","(-1600,1850)","0","pure_quanta","I2";
;
PART_NUMBER"DGA^7000023"
PART_TYPE"SMLF"
MATERIAL"IO"
VALUE"SOCKET4677_AZIF0045-P001C01CS"
$LOCATION"U1"
CDS_LIB"pure_quanta"
NEEDS_NO_SIZE"TRUE"
CDS_LMAN_SYM_OUTLINE"-1050,2150,1050,-2100"
CDS_LOCATION"U1"
$SEC"40"
CDS_SEC"40";
"VSS17"
$PN"AA19"5;
"VSS18"
$PN"AA23"5;
"VSS19"
$PN"AA25"5;
"VSS20"
$PN"AA29"5;
"VSS21"
$PN"AA31"5;
"VSS22"
$PN"AA35"5;
"VSS23"
$PN"AA37"5;
"VSS24"
$PN"AA41"5;
"VSS25"
$PN"AA43"5;
"VSS26"
$PN"AA48"5;
"VSS27"
$PN"AA50"5;
"VSS28"
$PN"AA54"5;
"VSS29"
$PN"AA56"5;
"VSS30"
$PN"AA60"5;
"VSS31"
$PN"AA62"5;
"VSS32"
$PN"AA66"5;
"VSS33"
$PN"AA68"5;
"VSS34"
$PN"AA72"5;
"VSS35"
$PN"AA74"5;
"VSS36"
$PN"AA78"5;
"VSS37"
$PN"AA80"5;
"VSS1690"
$PN"P32"4;
"VSS1696"
$PN"N76"4;
"VSS1697"
$PN"P51"4;
"VSS1698"
$PN"N78"4;
"VSS1699"
$PN"P57"4;
"VSS1700"
$PN"N80"4;
"VSS1701"
$PN"N82"4;
"VSS1702"
$PN"N84"4;
"VSS1703"
$PN"N88"4;
"VSS1704"
$PN"P71"4;
"VSS1705"
$PN"P12"4;
"VSS1706"
$PN"P16"4;
"VSS1707"
$PN"P20"4;
"VSS1708"
$PN"P22"4;
"VSS1709"
$PN"P26"4;
"VSS1710"
$PN"P28"4;
"VSS1711"
$PN"R1"4;
"VSS1712"
$PN"P34"4;
"VSS1713"
$PN"P38"4;
"VSS1714"
$PN"R19"4;
"VSS1715"
$PN"R23"4;
"VSS1716"
$PN"P4"4;
"VSS1717"
$PN"P40"4;
"VSS1718"
$PN"P44"4;
"VSS1719"
$PN"P47"4;
"VSS1720"
$PN"P53"4;
"VSS1721"
$PN"P59"4;
"VSS1722"
$PN"P63"4;
"VSS1723"
$PN"R48"4;
"VSS1724"
$PN"P65"4;
"VSS1725"
$PN"P69"4;
"VSS1726"
$PN"P75"4;
"VSS1727"
$PN"P77"4;
"VSS1728"
$PN"R60"4;
"VSS1729"
$PN"P8"4;
"VSS1730"
$PN"R66"4;
"VSS1731"
$PN"P87"4;
"VSS1732"
$PN"P91"4;
"VSS1733"
$PN"R13"4;
"VSS1734"
$PN"R17"4;
"VSS1735"
$PN"R25"4;
"VSS1736"
$PN"R29"4;
"VSS1737"
$PN"R31"4;
"VSS1738"
$PN"R35"4;
"VSS1739"
$PN"T12"4;
"VSS1740"
$PN"T16"4;
"VSS1741"
$PN"T18"4;
"VSS1742"
$PN"R37"4;
"VSS1743"
$PN"R41"4;
"VSS1744"
$PN"R43"4;
"VSS1745"
$PN"R5"4;
"VSS1746"
$PN"T36"4;
"VSS1747"
$PN"R50"4;
"VSS1748"
$PN"R54"4;
"VSS1749"
$PN"T49"4;
"VSS1750"
$PN"T55"4;
"VSS1751"
$PN"R56"4;
"VSS1752"
$PN"R62"4;
"VSS1753"
$PN"R68"4;
"VSS1754"
$PN"R72"4;
"VSS1755"
$PN"R74"4;
"VSS1756"
$PN"R78"4;
"VSS1757"
$PN"R84"4;
"VSS1758"
$PN"R88"4;
"VSS1759"
$PN"R9"4;
"VSS1760"
$PN"T24"4;
"VSS1761"
$PN"T30"4;
"VSS1762"
$PN"T4"4;
"VSS1763"
$PN"T42"4;
"VSS1764"
$PN"T61"4;
"VSS1765"
$PN"T67"4;
"VSS1766"
$PN"U52"4;
"VSS1767"
$PN"T73"4;
"VSS1768"
$PN"T79"4;
"VSS1769"
$PN"T8"4;
"VSS1770"
$PN"T83"4;
"VSS1771"
$PN"U39"4;
"VSS1772"
$PN"U82"4;
"VSS1773"
$PN"U84"4;
"VSS1774"
$PN"U88"4;
"VSS1775"
$PN"V12"5;
"VSS1776"
$PN"V16"5;
"VSS1777"
$PN"V18"5;
"VSS1778"
$PN"V20"5;
"VSS1779"
$PN"V22"5;
"VSS1780"
$PN"V24"5;
"VSS1781"
$PN"V26"5;
"VSS1782"
$PN"V28"5;
"VSS1783"
$PN"V30"5;
"VSS1784"
$PN"V32"5;
"VSS1785"
$PN"V34"5;
"VSS1786"
$PN"V36"5;
"VSS1787"
$PN"V38"5;
"VSS1788"
$PN"V4"5;
"VSS1789"
$PN"V49"5;
"VSS1790"
$PN"V40"5;
"VSS1791"
$PN"V42"5;
"VSS1792"
$PN"V44"5;
"VSS1793"
$PN"V47"5;
"VSS1794"
$PN"V51"5;
"VSS1795"
$PN"V53"5;
"VSS1796"
$PN"V55"5;
"VSS1797"
$PN"V57"5;
"VSS1798"
$PN"V59"5;
"VSS1799"
$PN"V61"5;
"VSS1800"
$PN"V71"5;
"VSS1801"
$PN"V73"5;
"VSS1802"
$PN"V63"5;
"VSS1803"
$PN"V65"5;
"VSS1804"
$PN"V67"5;
"VSS1805"
$PN"V69"5;
"VSS1806"
$PN"V75"5;
"VSS1807"
$PN"V91"5;
"VSS1808"
$PN"W1"5;
"VSS1809"
$PN"W13"5;
"VSS1810"
$PN"V77"5;
"VSS1811"
$PN"V79"5;
"VSS1812"
$PN"V8"5;
"VSS1813"
$PN"V87"5;
"VSS1814"
$PN"W5"5;
"VSS1815"
$PN"W52"5;
"VSS1816"
$PN"W39"5;
"VSS1817"
$PN"W84"5;
"VSS1818"
$PN"W88"5;
"VSS1819"
$PN"W9"5;
"VSS1820"
$PN"Y12"5;
"VSS1821"
$PN"Y16"5;
"VSS1822"
$PN"Y18"5;
"VSS1823"
$PN"Y24"5;
"VSS1824"
$PN"Y30"5;
"VSS1825"
$PN"Y36"5;
"VSS1826"
$PN"Y4"5;
"VSS1827"
$PN"Y42"5;
"VSS1828"
$PN"Y61"5;
"VSS1829"
$PN"Y67"5;
"VSS1830"
$PN"Y49"5;
"VSS1831"
$PN"Y55"5;
"VSS1832"
$PN"Y8"5;
"VSS1833"
$PN"Y73"5;
%"UNIVERSAL_GND"
"1","(-150,-675)","0","logical_power","I3";
;
CDS_LIB"logical_power"
HDL_POWER"GND";
"A"4;
%"UNIVERSAL_GND"
"1","(0,-675)","0","logical_power","I4";
;
CDS_LIB"logical_power"
HDL_POWER"GND";
"A"3;
%"SOCKET4677_AZIF0045P001C01CS"
"41","(1450,1850)","0","pure_quanta","I5";
;
PART_NUMBER"DGA^7000023"
PART_TYPE"SMLF"
VALUE"SOCKET4677_AZIF0045-P001C01CS"
MATERIAL"IO"
$LOCATION"U1"
CDS_LIB"pure_quanta"
NEEDS_NO_SIZE"TRUE"
CDS_LMAN_SYM_OUTLINE"-1050,2150,1050,-2100"
CDS_LOCATION"U1"
$SEC"41"
CDS_SEC"41";
"VSS1126"
$PN"E52"2;
"VSS1129"
$PN"E74"2;
"VSS1131"
$PN"E78"2;
"VSS1272"
$PN"E76"2;
"VSS1273"
$PN"E86"2;
"VSS1494"
$PN"F12"2;
"VSS1495"
$PN"F18"2;
"VSS1502"
$PN"F42"2;
"VSS1504"
$PN"F55"2;
"VSS1507"
$PN"F6"2;
"VSS1508"
$PN"F61"2;
"VSS1509"
$PN"F67"2;
"VSS1510"
$PN"F73"2;
"VSS1511"
$PN"F79"2;
"VSS1514"
$PN"G11"2;
"VSS1516"
$PN"G17"2;
"VSS1519"
$PN"G25"2;
"VSS1521"
$PN"G3"2;
"VSS1523"
$PN"G35"2;
"VSS1527"
$PN"G48"2;
"VSS1532"
$PN"G60"2;
"VSS1534"
$PN"G66"2;
"VSS1535"
$PN"G68"2;
"VSS1536"
$PN"G7"2;
"VSS1538"
$PN"G74"2;
"VSS1544"
$PN"H14"2;
"VSS1546"
$PN"H2"2;
"VSS1558"
$PN"H51"2;
"VSS1560"
$PN"H57"2;
"VSS1564"
$PN"H65"2;
"VSS1567"
$PN"H75"2;
"VSS1570"
$PN"F24"2;
"VSS1571"
$PN"F30"2;
"VSS1572"
$PN"F36"2;
"VSS1573"
$PN"F4"2;
"VSS1574"
$PN"F49"2;
"VSS1575"
$PN"J21"3;
"VSS1576"
$PN"F83"2;
"VSS1577"
$PN"F89"2;
"VSS1578"
$PN"G13"2;
"VSS1579"
$PN"G19"2;
"VSS1580"
$PN"J39"3;
"VSS1581"
$PN"G23"2;
"VSS1582"
$PN"J5"3;
"VSS1583"
$PN"G29"2;
"VSS1584"
$PN"G31"2;
"VSS1585"
$PN"G37"2;
"VSS1586"
$PN"G41"2;
"VSS1587"
$PN"J64"3;
"VSS1588"
$PN"G43"2;
"VSS1589"
$PN"J70"3;
"VSS1590"
$PN"G50"2;
"VSS1591"
$PN"G54"2;
"VSS1592"
$PN"G56"2;
"VSS1593"
$PN"G62"2;
"VSS1594"
$PN"G72"2;
"VSS1595"
$PN"J88"3;
"VSS1596"
$PN"J9"3;
"VSS1597"
$PN"K12"3;
"VSS1598"
$PN"K14"3;
"VSS1599"
$PN"K2"3;
"VSS1600"
$PN"G84"2;
"VSS1601"
$PN"G88"2;
"VSS1602"
$PN"K42"3;
"VSS1603"
$PN"K49"3;
"VSS1604"
$PN"G90"2;
"VSS1605"
$PN"H10"2;
"VSS1606"
$PN"H16"2;
"VSS1607"
$PN"H20"2;
"VSS1608"
$PN"H22"2;
"VSS1609"
$PN"H26"2;
"VSS1610"
$PN"H28"2;
"VSS1611"
$PN"H32"2;
"VSS1612"
$PN"H34"2;
"VSS1613"
$PN"H38"2;
"VSS1614"
$PN"L19"3;
"VSS1615"
$PN"H4"2;
"VSS1616"
$PN"H40"2;
"VSS1617"
$PN"H44"2;
"VSS1618"
$PN"H47"2;
"VSS1619"
$PN"H53"2;
"VSS1620"
$PN"H59"2;
"VSS1621"
$PN"H6"2;
"VSS1622"
$PN"H63"2;
"VSS1623"
$PN"H69"2;
"VSS1624"
$PN"H71"2;
"VSS1625"
$PN"H79"2;
"VSS1626"
$PN"H8"2;
"VSS1627"
$PN"H81"2;
"VSS1628"
$PN"J15"3;
"VSS1629"
$PN"J27"3;
"VSS1630"
$PN"J33"3;
"VSS1631"
$PN"J45"3;
"VSS1632"
$PN"J52"3;
"VSS1633"
$PN"J58"3;
"VSS1634"
$PN"L58"3;
"VSS1635"
$PN"J76"3;
"VSS1636"
$PN"J78"3;
"VSS1637"
$PN"J84"3;
"VSS1638"
$PN"J86"3;
"VSS1639"
$PN"K77"3;
"VSS1640"
$PN"L70"3;
"VSS1641"
$PN"K8"3;
"VSS1642"
$PN"K83"3;
"VSS1643"
$PN"K85"3;
"VSS1644"
$PN"L13"3;
"VSS1645"
$PN"L15"3;
"VSS1646"
$PN"L88"3;
"VSS1647"
$PN"L9"3;
"VSS1648"
$PN"L90"3;
"VSS1649"
$PN"M12"3;
"VSS1650"
$PN"L17"3;
"VSS1651"
$PN"L21"3;
"VSS1652"
$PN"M4"3;
"VSS1653"
$PN"M42"3;
"VSS1654"
$PN"M49"3;
"VSS1655"
$PN"L23"3;
"VSS1656"
$PN"L25"3;
"VSS1657"
$PN"M8"3;
"VSS1658"
$PN"L27"3;
"VSS1659"
$PN"L29"3;
"VSS1660"
$PN"L31"3;
"VSS1661"
$PN"L33"3;
"VSS1662"
$PN"L35"3;
"VSS1663"
$PN"L37"3;
"VSS1664"
$PN"N21"3;
"VSS1665"
$PN"L39"3;
"VSS1666"
$PN"L41"3;
"VSS1667"
$PN"L43"3;
"VSS1668"
$PN"L45"3;
"VSS1669"
$PN"N39"3;
"VSS1670"
$PN"L48"3;
"VSS1671"
$PN"L5"3;
"VSS1672"
$PN"L50"3;
"VSS1673"
$PN"L52"3;
"VSS1674"
$PN"L54"3;
"VSS1675"
$PN"N64"3;
"VSS1676"
$PN"L56"3;
"VSS1677"
$PN"L60"3;
"VSS1678"
$PN"L62"3;
"VSS1679"
$PN"L64"3;
"VSS1680"
$PN"L66"3;
"VSS1681"
$PN"L68"3;
"VSS1682"
$PN"L72"3;
"VSS1683"
$PN"L74"3;
"VSS1684"
$PN"L76"3;
"VSS1685"
$PN"L78"3;
"VSS1686"
$PN"M81"3;
"VSS1687"
$PN"M83"3;
"VSS1688"
$PN"N15"3;
"VSS1689"
$PN"N27"3;
"VSS1691"
$PN"N33"3;
"VSS1692"
$PN"N45"3;
"VSS1693"
$PN"N52"3;
"VSS1694"
$PN"N58"3;
"VSS1695"
$PN"N70"3;
%"UNIVERSAL_GND"
"1","(2900,-675)","0","logical_power","I6";
;
CDS_LIB"logical_power"
HDL_POWER"GND";
"A"2;
%"UNIVERSAL_GND"
"1","(3025,-675)","0","logical_power","I7";
;
CDS_LIB"logical_power"
HDL_POWER"GND";
"A"1;
%"SOCKET4677_AZIF0045P001C01CS"
"42","(4475,1900)","0","pure_quanta","I8";
;
PART_NUMBER"DGA^7000023"
PART_TYPE"SMLF"
MATERIAL"IO"
VALUE"SOCKET4677_AZIF0045-P001C01CS"
$LOCATION"U1"
CDS_LIB"pure_quanta"
NEEDS_NO_SIZE"TRUE"
CDS_LMAN_SYM_OUTLINE"-1050,2100,1050,-2050"
CDS_LOCATION"U1"
$SEC"42"
CDS_SEC"42";
"VSS1"
$PN"A11"1;
"VSS2"
$PN"A13"1;
"VSS3"
$PN"A17"1;
"VSS4"
$PN"A19"1;
"VSS5"
$PN"A23"1;
"VSS6"
$PN"A25"1;
"VSS7"
$PN"A29"1;
"VSS8"
$PN"A31"1;
"VSS9"
$PN"A35"1;
"VSS10"
$PN"A37"1;
"VSS11"
$PN"A41"1;
"VSS12"
$PN"A50"1;
"VSS13"
$PN"A54"1;
"VSS14"
$PN"A56"1;
"VSS15"
$PN"A60"1;
"VSS16"
$PN"A62"1;
"VSS378"
$PN"B12"1;
"VSS379"
$PN"B18"1;
"VSS380"
$PN"B24"1;
"VSS381"
$PN"B30"1;
"VSS382"
$PN"B36"1;
"VSS384"
$PN"B42"1;
"VSS385"
$PN"B49"1;
"VSS386"
$PN"B55"1;
"VSS387"
$PN"B6"1;
"VSS388"
$PN"B61"1;
"VSS389"
$PN"B67"1;
"VSS390"
$PN"B75"1;
"VSS391"
$PN"B83"1;
"VSS392"
$PN"B87"1;
"VSS609"
$PN"C39"1;
"VSS610"
$PN"C45"1;
"VSS612"
$PN"C5"1;
"VSS613"
$PN"C52"1;
"VSS614"
$PN"C72"1;
"VSS615"
$PN"C74"1;
"VSS616"
$PN"C78"1;
"VSS617"
$PN"C80"1;
"VSS618"
$PN"C82"1;
"VSS619"
$PN"C86"1;
"VSS657"
$PN"D63"1;
"VSS658"
$PN"D65"1;
"VSS659"
$PN"D67"1;
"VSS662"
$PN"D79"1;
"VSS663"
$PN"D8"1;
"VSS864"
$PN"D10"1;
"VSS865"
$PN"D12"1;
"VSS866"
$PN"D14"1;
"VSS868"
$PN"D16"1;
"VSS869"
$PN"D18"1;
"VSS871"
$PN"D20"1;
"VSS873"
$PN"D22"1;
"VSS874"
$PN"D24"1;
"VSS875"
$PN"D26"1;
"VSS876"
$PN"D28"1;
"VSS877"
$PN"D30"1;
"VSS878"
$PN"D32"1;
"VSS879"
$PN"D34"1;
"VSS881"
$PN"D36"1;
"VSS884"
$PN"D38"1;
"VSS885"
$PN"D40"1;
"VSS886"
$PN"D42"1;
"VSS888"
$PN"D44"1;
"VSS889"
$PN"D47"1;
"VSS891"
$PN"D49"1;
"VSS892"
$PN"D51"1;
"VSS895"
$PN"D53"1;
"VSS896"
$PN"D55"1;
"VSS897"
$PN"D57"1;
"VSS898"
$PN"D59"1;
"VSS899"
$PN"D6"1;
"VSS900"
$PN"D61"1;
"VSS901"
$PN"D69"1;
"VSS902"
$PN"D71"1;
"VSS906"
$PN"D81"1;
"VSS907"
$PN"D83"1;
"VSS1125"
$PN"E5"1;
"VSS1271"
$PN"E39"1;
END.
